(kicad_pcb
	(version 20241229)
	(generator "pcbnew")
	(generator_version "9.0")
	(general
		(thickness 1.711)
		(legacy_teardrops no)
	)
	(paper "A4")
	(title_block
		(title "Antmicro Baseboard for Jetson AGX Thor")
		(date "2026-02-18")
		(rev "1.1.0")
		(company "Antmicro Ltd")
		(comment 1 "www.antmicro.com")
		(comment 9 "footprints 288-291 of 1170")
	)
	(layers
		(0 "F.Cu" signal)
		(4 "In1.Cu" signal)
		(6 "In2.Cu" signal)
		(8 "In3.Cu" signal)
		(10 "In4.Cu" jumper)
		(12 "In5.Cu" signal)
		(14 "In6.Cu" signal)
		(16 "In7.Cu" signal)
		(18 "In8.Cu" signal)
		(2 "B.Cu" signal)
		(9 "F.Adhes" user "F.Adhesive")
		(11 "B.Adhes" user "B.Adhesive")
		(13 "F.Paste" user)
		(15 "B.Paste" user)
		(5 "F.SilkS" user "F.Silkscreen")
		(7 "B.SilkS" user "B.Silkscreen")
		(1 "F.Mask" user)
		(3 "B.Mask" user)
		(17 "Dwgs.User" user "User.Drawings")
		(19 "Cmts.User" user "User.Comments")
		(21 "Eco1.User" user "User.Eco1")
		(23 "Eco2.User" user "User.Eco2")
		(25 "Edge.Cuts" user)
		(27 "Margin" user)
		(31 "F.CrtYd" user "F.Courtyard")
		(29 "B.CrtYd" user "B.Courtyard")
		(35 "F.Fab" user)
		(33 "B.Fab" user)
	)
	(footprint "antmicro-footprints:D_SOD-123"
		(layer "F.Cu")
		(at 224.75 73.5 -90)
		(property "Reference" "D2"
			(at 0 -1.099999 90)
			(layer "F.SilkS")
			(effects
				(font
					(size 0.7 0.7)
					(thickness 0.15)
				)
				(justify right top)
			)
		)
		(property "Value" "PTVS26VS1UR,115"
			(at 0 1.95 90)
			(layer "F.Fab")
			(effects
				(font
					(size 0.7 0.7)
					(thickness 0.15)
				)
				(justify right top)
			)
		)
		(property "Datasheet" "https://www.mouser.com/datasheet/2/916/PTVSXS1UR_SER-1545507.pdf"
			(at 0 0 90)
			(layer "F.Fab")
			(hide yes)
			(effects
				(font
					(size 1.27 1.27)
					(thickness 0.15)
				)
			)
		)
		(property "Description" "Unidirectional TVS, 8 kV,  SOD-123F, 26 V, 400 W"
			(at 0 0 90)
			(layer "F.Fab")
			(hide yes)
			(effects
				(font
					(size 1.27 1.27)
					(thickness 0.15)
				)
			)
		)
		(property "Manufacturer" "Nexperia"
			(at 0 0 90)
			(unlocked yes)
			(layer "F.Fab")
			(hide yes)
			(effects
				(font
					(size 1 1)
					(thickness 0.15)
				)
			)
		)
		(property "MPN" "PTVS26VS1UR,115"
			(at 0 0 90)
			(unlocked yes)
			(layer "F.Fab")
			(hide yes)
			(effects
				(font
					(size 1 1)
					(thickness 0.15)
				)
			)
		)
		(property "Author" "Antmicro"
			(at 0 0 90)
			(unlocked yes)
			(layer "F.Fab")
			(hide yes)
			(effects
				(font
					(size 1 1)
					(thickness 0.15)
				)
			)
		)
		(property "License" "Apache-2.0"
			(at 0 0 90)
			(unlocked yes)
			(layer "F.Fab")
			(hide yes)
			(effects
				(font
					(size 1 1)
					(thickness 0.15)
				)
			)
		)
		(sheetname "/Power/")
		(sheetfile "power.kicad_sch")
		(attr smd)
		(fp_line
			(start 1.1 0.8875)
			(end 1.45 0.8875)
			(stroke
				(width 0.15)
				(type solid)
			)
			(layer "F.SilkS")
		)
		(fp_line
			(start -1.45 0.8625)
			(end -1.45 0.5875)
			(stroke
				(width 0.15)
				(type solid)
			)
			(layer "F.SilkS")
		)
		(fp_line
			(start -1.1 0.8625)
			(end -1.45 0.8625)
			(stroke
				(width 0.15)
				(type solid)
			)
			(layer "F.SilkS")
		)
		(fp_line
			(start 1.45 0.6125)
			(end 1.45 0.8875)
			(stroke
				(width 0.15)
				(type solid)
			)
			(layer "F.SilkS")
		)
		(fp_line
			(start -0.925 -0.5)
			(end -0.925 0.5)
			(stroke
				(width 0.15)
				(type solid)
			)
			(layer "F.SilkS")
		)
		(fp_line
			(start -1.45 -0.6)
			(end -1.45 -0.875)
			(stroke
				(width 0.15)
				(type solid)
			)
			(layer "F.SilkS")
		)
		(fp_line
			(start -1.1 -0.875)
			(end -1.45 -0.875)
			(stroke
				(width 0.15)
				(type solid)
			)
			(layer "F.SilkS")
		)
		(fp_line
			(start 1.1 -0.875)
			(end 1.45 -0.875)
			(stroke
				(width 0.15)
				(type solid)
			)
			(layer "F.SilkS")
		)
		(fp_line
			(start 1.45 -0.875)
			(end 1.45 -0.6)
			(stroke
				(width 0.15)
				(type solid)
			)
			(layer "F.SilkS")
		)
		(fp_poly
			(pts
				(xy -2.275 -1.05) (xy 2.275 -1.05) (xy 2.275 1.05) (xy -2.275 1.05)
			)
			(stroke
				(width 0.05)
				(type solid)
			)
			(fill no)
			(layer "F.CrtYd")
		)
		(fp_line
			(start -1.325 0.848)
			(end 1.324 0.848)
			(stroke
				(width 0.15)
				(type solid)
			)
			(layer "F.Fab")
		)
		(fp_line
			(start -1.325 -0.85)
			(end -1.325 0.848)
			(stroke
				(width 0.15)
				(type solid)
			)
			(layer "F.Fab")
		)
		(fp_line
			(start -1.325 -0.85)
			(end 1.324 -0.85)
			(stroke
				(width 0.15)
				(type solid)
			)
			(layer "F.Fab")
		)
		(fp_line
			(start 1.324 -0.85)
			(end 1.324 0.848)
			(stroke
				(width 0.15)
				(type solid)
			)
			(layer "F.Fab")
		)
		(fp_text user "License: Apache-2.0"
			(at -2.36 5.85 90)
			(layer "F.Fab")
			(effects
				(font
					(size 0.7 0.7)
					(thickness 0.15)
				)
				(justify right top)
			)
		)
		(fp_text user "${REFERENCE}"
			(at -2.36 3.299999 90)
			(layer "F.Fab")
			(effects
				(font
					(size 0.7 0.7)
					(thickness 0.15)
				)
				(justify right top)
			)
		)
		(fp_text user "Author: Antmicro"
			(at -2.36 4.6 90)
			(layer "F.Fab")
			(effects
				(font
					(size 0.7 0.7)
					(thickness 0.15)
				)
				(justify right top)
			)
		)
		(pad "1" smd roundrect
			(at -1.625 -0.001001 270)
			(size 0.9 0.95)
			(layers "F.Cu" "F.Mask" "F.Paste")
			(roundrect_rratio 0.15)
			(net 3 "VCC_IN")
			(pinfunction "C")
			(pintype "passive")
		)
		(pad "2" smd roundrect
			(at 1.625 -0.001001 270)
			(size 0.9 0.95)
			(layers "F.Cu" "F.Mask" "F.Paste")
			(roundrect_rratio 0.15)
			(net 1 "GND")
			(pinfunction "A")
			(pintype "passive")
		)
	)
	(footprint "antmicro-footprints:USON-10_2.5x1mm_P0.5mm"
		(layer "F.Cu")
		(at 221.369 102.36)
		(descr "USON-10 2.5x1mm_ Pitch 0.5mm")
		(tags "USON-10 2.5x1mm Pitch 0.5mm")
		(property "Reference" "U58"
			(at 1.861 1 90)
			(layer "F.SilkS")
			(effects
				(font
					(size 0.7 0.7)
					(thickness 0.15)
				)
				(justify left bottom)
			)
		)
		(property "Value" "TPD4E05U06QDQARQ1"
			(at 0.018 2.499 0)
			(layer "F.Fab")
			(effects
				(font
					(size 0.7 0.7)
					(thickness 0.15)
				)
				(justify left bottom)
			)
		)
		(property "Datasheet" "https://www.ti.com/lit/ds/symlink/tpd4e05u06-q1.pdf?HQS=dis-mous-null-mousermode-dsf-pf-null-wwe&ts=1663591265741&ref_url=https%253A%252F%252Fwww.mouser.com%252F"
			(at 0 0 0)
			(layer "F.Fab")
			(hide yes)
			(effects
				(font
					(size 1.27 1.27)
					(thickness 0.15)
				)
			)
		)
		(property "Description" "TVS diode array, 12 kV, USON-10, 5.5 V, 0.5 pF"
			(at 0 0 0)
			(layer "F.Fab")
			(hide yes)
			(effects
				(font
					(size 1.27 1.27)
					(thickness 0.15)
				)
			)
		)
		(property "Manufacturer" "Texas Instruments"
			(at 0 0 0)
			(unlocked yes)
			(layer "F.Fab")
			(hide yes)
			(effects
				(font
					(size 1 1)
					(thickness 0.15)
				)
			)
		)
		(property "MPN" "TPD4E05U06QDQARQ1"
			(at 0 0 0)
			(unlocked yes)
			(layer "F.Fab")
			(hide yes)
			(effects
				(font
					(size 1 1)
					(thickness 0.15)
				)
			)
		)
		(property "Author" "Antmicro"
			(at 0 0 0)
			(unlocked yes)
			(layer "F.Fab")
			(hide yes)
			(effects
				(font
					(size 1 1)
					(thickness 0.15)
				)
			)
		)
		(property "License" "Apache-2.0"
			(at 0 0 0)
			(unlocked yes)
			(layer "F.Fab")
			(hide yes)
			(effects
				(font
					(size 1 1)
					(thickness 0.15)
				)
			)
		)
		(sheetname "/Recovery USB/")
		(sheetfile "recovery_usb.kicad_sch")
		(attr smd)
		(fp_line
			(start 0.498 -1.401)
			(end -0.5 -1.401)
			(stroke
				(width 0.15)
				(type solid)
			)
			(layer "F.SilkS")
		)
		(fp_line
			(start 0.498 1.398)
			(end -0.5 1.398)
			(stroke
				(width 0.15)
				(type solid)
			)
			(layer "F.SilkS")
		)
		(fp_circle
			(center -0.68 -1.27)
			(end -0.63 -1.27)
			(stroke
				(width 0.15)
				(type solid)
			)
			(fill yes)
			(layer "F.SilkS")
		)
		(fp_rect
			(start -0.8 -1.5)
			(end 0.8 1.499)
			(stroke
				(width 0.05)
				(type solid)
			)
			(fill no)
			(layer "F.CrtYd")
		)
		(fp_line
			(start -0.5 -1)
			(end -0.5 1.249)
			(stroke
				(width 0.15)
				(type solid)
			)
			(layer "F.Fab")
		)
		(fp_line
			(start -0.5 1.249)
			(end 0.498 1.249)
			(stroke
				(width 0.15)
				(type solid)
			)
			(layer "F.Fab")
		)
		(fp_line
			(start -0.25 -1.25)
			(end -0.5 -1)
			(stroke
				(width 0.15)
				(type solid)
			)
			(layer "F.Fab")
		)
		(fp_line
			(start 0.498 -1.25)
			(end -0.25 -1.25)
			(stroke
				(width 0.15)
				(type solid)
			)
			(layer "F.Fab")
		)
		(fp_line
			(start 0.498 -1.25)
			(end 0.498 1.249)
			(stroke
				(width 0.15)
				(type solid)
			)
			(layer "F.Fab")
		)
		(fp_text user "License: Apache-2.0"
			(at -0.802 6.9 0)
			(layer "F.Fab")
			(effects
				(font
					(size 0.7 0.7)
					(thickness 0.15)
				)
				(justify left bottom)
			)
		)
		(fp_text user "${REFERENCE}"
			(at -0.802 4.498 0)
			(layer "F.Fab")
			(effects
				(font
					(size 0.7 0.7)
					(thickness 0.15)
				)
				(justify left bottom)
			)
		)
		(fp_text user "Author: Antmicro"
			(at -0.802 5.7 0)
			(layer "F.Fab")
			(effects
				(font
					(size 0.7 0.7)
					(thickness 0.15)
				)
				(justify left bottom)
			)
		)
		(pad "1" smd roundrect
			(at -0.387 -1 270)
			(size 0.25 0.55)
			(layers "F.Cu" "F.Mask" "F.Paste")
			(roundrect_rratio 0.25)
			(net 766 "/Recovery USB/USB0.D+")
			(pintype "passive")
		)
		(pad "2" smd roundrect
			(at -0.387 -0.5 270)
			(size 0.25 0.55)
			(layers "F.Cu" "F.Mask" "F.Paste")
			(roundrect_rratio 0.25)
			(net 698 "/Recovery USB/USB0.D-")
			(pintype "passive")
		)
		(pad "3" smd roundrect
			(at -0.387 0 270)
			(size 0.4 0.55)
			(layers "F.Cu" "F.Mask" "F.Paste")
			(roundrect_rratio 0.25)
			(net 1 "GND")
			(pintype "power_in")
		)
		(pad "4" smd roundrect
			(at -0.387 0.498 270)
			(size 0.25 0.55)
			(layers "F.Cu" "F.Mask" "F.Paste")
			(roundrect_rratio 0.25)
			(net 801 "/Recovery USB/USBC2_CC2")
			(pintype "passive")
		)
		(pad "5" smd roundrect
			(at -0.387 0.998 270)
			(size 0.25 0.55)
			(layers "F.Cu" "F.Mask" "F.Paste")
			(roundrect_rratio 0.25)
			(net 806 "/Recovery USB/USBC2_CC1")
			(pintype "passive")
		)
		(pad "6" smd roundrect
			(at 0.385 0.998 270)
			(size 0.25 0.55)
			(layers "F.Cu" "F.Mask" "F.Paste")
			(roundrect_rratio 0.25)
			(net 806 "/Recovery USB/USBC2_CC1")
			(pintype "passive")
		)
		(pad "7" smd roundrect
			(at 0.385 0.498 270)
			(size 0.25 0.55)
			(layers "F.Cu" "F.Mask" "F.Paste")
			(roundrect_rratio 0.25)
			(net 801 "/Recovery USB/USBC2_CC2")
			(pintype "passive")
		)
		(pad "8" smd roundrect
			(at 0.385 0 270)
			(size 0.4 0.55)
			(layers "F.Cu" "F.Mask" "F.Paste")
			(roundrect_rratio 0.25)
			(net 1 "GND")
			(pintype "passive")
		)
		(pad "9" smd roundrect
			(at 0.385 -0.5 270)
			(size 0.25 0.55)
			(layers "F.Cu" "F.Mask" "F.Paste")
			(roundrect_rratio 0.25)
			(net 698 "/Recovery USB/USB0.D-")
			(pintype "passive")
		)
		(pad "10" smd roundrect
			(at 0.385 -1 270)
			(size 0.25 0.55)
			(layers "F.Cu" "F.Mask" "F.Paste")
			(roundrect_rratio 0.25)
			(net 766 "/Recovery USB/USB0.D+")
			(pintype "passive")
		)
	)
	(footprint "antmicro-footprints:R_0402_1005Metric"
		(layer "F.Cu")
		(at 74.5 78.8 90)
		(descr "Resistor SMD 0402")
		(tags "resistor SMD 0402")
		(property "Reference" "R350"
			(at -1.8 -0.7 90)
			(layer "F.SilkS")
			(effects
				(font
					(size 0.7 0.7)
					(thickness 0.15)
				)
				(justify left bottom)
			)
		)
		(property "Value" "R_100R_0402"
			(at -1.011843 1.772046 90)
			(layer "F.Fab")
			(effects
				(font
					(size 0.7 0.7)
					(thickness 0.15)
				)
				(justify left bottom)
			)
		)
		(property "Datasheet" "https://www.bourns.com/docs/product-datasheets/cr.pdf"
			(at 0 0 90)
			(layer "F.Fab")
			(hide yes)
			(effects
				(font
					(size 1.27 1.27)
					(thickness 0.15)
				)
			)
		)
		(property "Description" "SMD Chip Resistor, 100 ohm, ± 1%, 62.5 mW, 0402 [1005 Metric], Thick Film, General Purpose"
			(at 0 0 90)
			(layer "F.Fab")
			(hide yes)
			(effects
				(font
					(size 1.27 1.27)
					(thickness 0.15)
				)
			)
		)
		(property "MPN" "CR0402-FX-1000GLF"
			(at 0 0 90)
			(unlocked yes)
			(layer "F.Fab")
			(hide yes)
			(effects
				(font
					(size 1 1)
					(thickness 0.15)
				)
			)
		)
		(property "Manufacturer" "Bourns"
			(at 0 0 90)
			(unlocked yes)
			(layer "F.Fab")
			(hide yes)
			(effects
				(font
					(size 1 1)
					(thickness 0.15)
				)
			)
		)
		(property "License" "Apache-2.0"
			(at 0 0 90)
			(unlocked yes)
			(layer "F.Fab")
			(hide yes)
			(effects
				(font
					(size 1 1)
					(thickness 0.15)
				)
			)
		)
		(property "Author" "Antmicro"
			(at 0 0 90)
			(unlocked yes)
			(layer "F.Fab")
			(hide yes)
			(effects
				(font
					(size 1 1)
					(thickness 0.15)
				)
			)
		)
		(property "Val" "100R"
			(at 0 0 90)
			(unlocked yes)
			(layer "F.Fab")
			(hide yes)
			(effects
				(font
					(size 1 1)
					(thickness 0.15)
				)
			)
		)
		(property "Tolerance" "1%"
			(at 0 0 90)
			(unlocked yes)
			(layer "F.Fab")
			(hide yes)
			(effects
				(font
					(size 1 1)
					(thickness 0.15)
				)
			)
		)
		(sheetname "/Expansion connector/")
		(sheetfile "expansion_connector.kicad_sch")
		(attr smd)
		(fp_poly
			(pts
				(xy -0.925 -0.47) (xy 0.925 -0.47) (xy 0.925 0.47) (xy -0.925 0.47)
			)
			(stroke
				(width 0.05)
				(type default)
			)
			(fill no)
			(layer "F.CrtYd")
		)
		(fp_poly
			(pts
				(xy -0.5 -0.25) (xy 0.5 -0.25) (xy 0.5 0.25) (xy -0.5 0.25)
			)
			(stroke
				(width 0.15)
				(type solid)
			)
			(fill no)
			(layer "F.Fab")
		)
		(fp_text user "${REFERENCE}"
			(at -0.95 3.168 90)
			(layer "F.Fab")
			(effects
				(font
					(size 0.7 0.7)
					(thickness 0.15)
				)
				(justify left bottom)
			)
		)
		(fp_text user "License: Apache-2.0"
			(at -0.949999 5.169 90)
			(layer "F.Fab")
			(effects
				(font
					(size 0.7 0.7)
					(thickness 0.15)
				)
				(justify left bottom)
			)
		)
		(fp_text user "Author: Antmicro"
			(at -0.95 4.169 90)
			(layer "F.Fab")
			(effects
				(font
					(size 0.7 0.7)
					(thickness 0.15)
				)
				(justify left bottom)
			)
		)
		(pad "1" smd roundrect
			(at -0.48 0 90)
			(size 0.59 0.64)
			(layers "F.Cu" "F.Mask" "F.Paste")
			(roundrect_rratio 0.25)
			(net 761 "Net-(J18-PadH02)")
			(pintype "passive")
		)
		(pad "2" smd roundrect
			(at 0.48 0 90)
			(size 0.59 0.64)
			(layers "F.Cu" "F.Mask" "F.Paste")
			(roundrect_rratio 0.25)
			(net 319 "/Expansion connector/FMC_PRSNT_M2C_L")
			(pintype "passive")
		)
	)
	(footprint "antmicro-footprints:C_0603_1608Metric_EIA"
		(layer "F.Cu")
		(at 174.9 130.18 -90)
		(descr "Capacitor SMD 0603, IPC-7351 Density Level A")
		(tags "Capacitor 0603")
		(property "Reference" "C73"
			(at -4.28 9.4 90)
			(layer "F.SilkS")
			(effects
				(font
					(size 0.7 0.7)
					(thickness 0.15)
				)
				(justify right top)
			)
		)
		(property "Value" "C_22u_16V_0603"
			(at -1.42757 1.770288 90)
			(layer "F.Fab")
			(effects
				(font
					(size 0.7 0.7)
					(thickness 0.15)
				)
				(justify right top)
			)
		)
		(property "Datasheet" "https://product.samsungsem.com/mlcc/CL10A226MO7JZN.do"
			(at 0 0 90)
			(layer "F.Fab")
			(hide yes)
			(effects
				(font
					(size 1.27 1.27)
					(thickness 0.15)
				)
			)
		)
		(property "Description" "SMD Multilayer Ceramic Capacitor"
			(at 0 0 90)
			(layer "F.Fab")
			(hide yes)
			(effects
				(font
					(size 1.27 1.27)
					(thickness 0.15)
				)
			)
		)
		(property "Manufacturer" "Samsung Electro-Mechanics"
			(at 0 0 270)
			(unlocked yes)
			(layer "F.Fab")
			(hide yes)
			(effects
				(font
					(size 1 1)
					(thickness 0.15)
				)
			)
		)
		(property "MPN" "CL10A226MO7JZNC"
			(at 0 0 270)
			(unlocked yes)
			(layer "F.Fab")
			(hide yes)
			(effects
				(font
					(size 1 1)
					(thickness 0.15)
				)
			)
		)
		(property "Val" "22u"
			(at 0 0 270)
			(unlocked yes)
			(layer "F.Fab")
			(hide yes)
			(effects
				(font
					(size 1 1)
					(thickness 0.15)
				)
			)
		)
		(property "License" "Apache-2.0"
			(at 0 0 270)
			(unlocked yes)
			(layer "F.Fab")
			(hide yes)
			(effects
				(font
					(size 1 1)
					(thickness 0.15)
				)
			)
		)
		(property "Author" "Antmicro"
			(at 0 0 270)
			(unlocked yes)
			(layer "F.Fab")
			(hide yes)
			(effects
				(font
					(size 1 1)
					(thickness 0.15)
				)
			)
		)
		(property "Voltage" "16V"
			(at 0 0 270)
			(unlocked yes)
			(layer "F.Fab")
			(hide yes)
			(effects
				(font
					(size 1 1)
					(thickness 0.15)
				)
			)
		)
		(property "Dielectric" ""
			(at 0 0 270)
			(unlocked yes)
			(layer "F.Fab")
			(hide yes)
			(effects
				(font
					(size 1 1)
					(thickness 0.15)
				)
			)
		)
		(sheetname "/DCDC/")
		(sheetfile "dcdc.kicad_sch")
		(attr smd)
		(fp_line
			(start -0.15 0.55)
			(end 0.15 0.55)
			(stroke
				(width 0.15)
				(type solid)
			)
			(layer "F.SilkS")
		)
		(fp_line
			(start -0.15 -0.55)
			(end 0.15 -0.55)
			(stroke
				(width 0.15)
				(type solid)
			)
			(layer "F.SilkS")
		)
		(fp_rect
			(start -1.25 -0.65)
			(end 1.25 0.65)
			(stroke
				(width 0.05)
				(type solid)
			)
			(fill no)
			(layer "F.CrtYd")
		)
		(fp_rect
			(start -0.8 -0.45)
			(end 0.8 0.45)
			(stroke
				(width 0.15)
				(type solid)
			)
			(fill no)
			(layer "F.Fab")
		)
		(fp_text user "Author: Antmicro"
			(at -1.682 4.894 90)
			(layer "F.Fab")
			(effects
				(font
					(size 0.7 0.7)
					(thickness 0.15)
				)
				(justify right top)
			)
		)
		(fp_text user "${REFERENCE}"
			(at -1.682 3.895 90)
			(layer "F.Fab")
			(effects
				(font
					(size 0.7 0.7)
					(thickness 0.15)
				)
				(justify right top)
			)
		)
		(fp_text user "License: Apache-2.0"
			(at -1.682 5.895 90)
			(layer "F.Fab")
			(effects
				(font
					(size 0.7 0.7)
					(thickness 0.15)
				)
				(justify right top)
			)
		)
		(pad "1" smd roundrect
			(at -0.7 0 270)
			(size 0.8 1.1)
			(layers "F.Cu" "F.Mask" "F.Paste")
			(roundrect_rratio 0.2)
			(net 1 "GND")
			(pintype "passive")
		)
		(pad "2" smd roundrect
			(at 0.7 0 270)
			(size 0.8 1.1)
			(layers "F.Cu" "F.Mask" "F.Paste")
			(roundrect_rratio 0.2)
			(net 567 "/DCDC/3V3_OUT")
			(pintype "passive")
		)
	)
)
